# S9S_MB_2U (Grand Teton) — schematic netlist excerpt (pin names and nets, part order shuffled) for the footprints in the layout excerpt that follows; sources: Cadence DE-HDL packaged netlist, KiCad conversion of 03242023_DA0F0TMBIJ0_F0T_Motherboard_J_brd_V01_OCP.brd

PC1594  Q_CAPP  330UF 2V 35% SPCAP  pkg SMLF  page 293 : A = PVCCINFAON_CPU1 ; B = GND

(kicad_pcb
	(version 20260206)
	(generator "pcbnew")
	(generator_version "10.0")
	(general
		(thickness 1.6)
		(legacy_teardrops no)
	)
	(paper "A4")
	(title_block
		(title "03242023_DA0F0TMBIJ0_F0T_Motherboard_J_brd_V01_OCP.brd")
		(comment 1 "Grand Teton / footprints 5761-5761 of 6105")
	)
	(layers
		(0 "F.Cu" signal "TOP")
		(4 "In1.Cu" signal "GND")
		(6 "In2.Cu" signal "IN1")
		(8 "In3.Cu" signal "GND1")
		(10 "In4.Cu" signal "IN2")
		(12 "In5.Cu" signal "GND2")
		(14 "In6.Cu" signal "IN3")
		(16 "In7.Cu" signal "GND3")
		(18 "In8.Cu" signal "VCC")
		(20 "In9.Cu" signal "VCC1")
		(22 "In10.Cu" signal "GND4")
		(24 "In11.Cu" signal "IN4")
		(26 "In12.Cu" signal "GND5")
		(28 "In13.Cu" signal "IN5")
		(30 "In14.Cu" signal "GND6")
		(32 "In15.Cu" signal "IN6")
		(34 "In16.Cu" signal "GND7")
		(2 "B.Cu" signal "BOTTOM")
		(9 "F.Adhes" user "F.Adhesive")
		(11 "B.Adhes" user "B.Adhesive")
		(13 "F.Paste" user "Package Geometry/Pastemask Top")
		(15 "B.Paste" user "Package Geometry/Pastemask Bottom")
		(5 "F.SilkS" user "Ref Des/Silkscreen Top")
		(7 "B.SilkS" user "Ref Des/Silkscreen Bottom")
		(1 "F.Mask" user "Board Geometry/Soldermask Top")
		(3 "B.Mask" user "Board Geometry/Soldermask Bottom")
		(17 "Dwgs.User" user "User.Drawings")
		(19 "Cmts.User" user "User.Comments")
		(21 "Eco1.User" user "User.Eco1")
		(23 "Eco2.User" user "User.Eco2")
		(25 "Edge.Cuts" user "Board Geometry/Outline")
		(27 "Margin" user)
		(31 "F.CrtYd" user "Package Geometry/Place Bound Top")
		(29 "B.CrtYd" user "Package Geometry/Place Bound Bottom")
		(35 "F.Fab" user "Ref Des/Assembly Top")
		(33 "B.Fab" user "Ref Des/Assembly Bottom")
	)
	(footprint ""
		(layer "B.Cu")
		(at 61.62421 -156.47797)
		(property "Reference" "PC1594"
			(at 0 0 0)
			(layer "B.SilkS")
			(hide yes)
			(effects
				(font
					(size 1.27 1.27)
				)
				(justify mirror)
			)
		)
		(property "Value" ""
			(at 0 0 0)
			(layer "B.Fab")
			(effects
				(font
					(size 1.27 1.27)
				)
				(justify mirror)
			)
		)
		(duplicate_pad_numbers_are_jumpers no)
		(fp_line
			(start -4.53898 -2.15011)
			(end -4.53898 2.15011)
			(stroke
				(width 0.1524)
				(type default)
			)
			(layer "B.SilkS")
		)
		(fp_line
			(start -4.53898 2.15011)
			(end 4.53898 2.15011)
			(stroke
				(width 0.1524)
				(type default)
			)
			(layer "B.SilkS")
		)
		(fp_line
			(start 4.53898 -2.150618)
			(end 4.539742 2.152142)
			(stroke
				(width 0.1524)
				(type default)
			)
			(layer "B.SilkS")
		)
		(fp_line
			(start 4.53898 -2.15011)
			(end -4.53898 -2.15011)
			(stroke
				(width 0.1524)
				(type default)
			)
			(layer "B.SilkS")
		)
		(fp_line
			(start 4.53898 2.15011)
			(end 4.53898 -2.15011)
			(stroke
				(width 0.1524)
				(type default)
			)
			(layer "B.SilkS")
		)
		(fp_line
			(start 4.69138 -2.150618)
			(end 4.692396 2.161032)
			(stroke
				(width 0.1524)
				(type default)
			)
			(layer "B.SilkS")
		)
		(fp_line
			(start 4.83108 2.150364)
			(end 4.447794 2.149348)
			(stroke
				(width 0.1524)
				(type default)
			)
			(layer "B.SilkS")
		)
		(fp_line
			(start 4.84378 -2.150618)
			(end 4.53898 -2.150618)
			(stroke
				(width 0.1524)
				(type default)
			)
			(layer "B.SilkS")
		)
		(fp_line
			(start 4.84378 -2.150618)
			(end 4.842256 2.163064)
			(stroke
				(width 0.1524)
				(type default)
			)
			(layer "B.SilkS")
		)
		(fp_line
			(start -3.64998 -2.15011)
			(end -3.64998 2.15011)
			(stroke
				(width 0.1)
				(type default)
			)
			(layer "B.Fab")
		)
		(fp_line
			(start -3.64998 2.15011)
			(end 3.64998 2.15011)
			(stroke
				(width 0.1)
				(type default)
			)
			(layer "B.Fab")
		)
		(fp_line
			(start 3.64998 -2.15011)
			(end -3.64998 -2.15011)
			(stroke
				(width 0.1)
				(type default)
			)
			(layer "B.Fab")
		)
		(fp_line
			(start 3.64998 2.15011)
			(end 3.64998 -2.15011)
			(stroke
				(width 0.1)
				(type default)
			)
			(layer "B.Fab")
		)
		(fp_text user "-"
			(at -4.79425 0.764032 0)
			(unlocked yes)
			(layer "B.SilkS")
			(effects
				(font
					(size 1.905 1.4224)
					(thickness 0.1524)
				)
				(justify left mirror)
			)
		)
		(fp_text user "+"
			(at 6.214872 -0.337058 0)
			(unlocked yes)
			(layer "B.SilkS")
			(effects
				(font
					(size 1.905 1.4224)
					(thickness 0.1524)
				)
				(justify left mirror)
			)
		)
		(fp_text user "-"
			(at -4.313174 -0.094488 0)
			(unlocked yes)
			(layer "B.Fab")
			(effects
				(font
					(size 1.905 1.4224)
					(thickness 0.1524)
				)
				(justify left mirror)
			)
		)
		(fp_text user "+"
			(at 6.214872 -0.337058 0)
			(unlocked yes)
			(layer "B.Fab")
			(effects
				(font
					(size 1.905 1.4224)
					(thickness 0.1524)
				)
				(justify left mirror)
			)
		)
		(pad "1" smd rect
			(at 3.199892 0 180)
			(size 2.413 2.8194)
			(layers "B.Cu" "B.Mask" "B.Paste")
			(net "PVCCINFAON_CPU1")
		)
		(pad "2" smd rect
			(at -3.199892 0 180)
			(size 2.413 2.8194)
			(layers "B.Cu" "B.Mask" "B.Paste")
			(net "GND")
		)
	)
)
